( ConstraintFile "p3v3"
	( constraintHeader
		( objectKey
			( logical )
		)
		( version
			( 16.5 )
		)
		( revisionNumber
			( logicalViewRevNum 2 )
			( physicalViewRevNum 0 )
			( otherViewRevNum 0 )
		)
		( contents
			( dictionaryExtensions )
			( worksheetCustomizations )
			( electricalConstraints )
			( netClasses )
			( properties )
		)
		( precision
			( units mil )
			( numberOfDecimalPlaces 2 )
		)
	)
	( DictionaryExtensions
		( Attribute
			( Name "MATERIAL" )
			( Description " " )
			( Value
				( DataType ( dString ) )
				( Status  sProperty  sPackage )
			)
			( Objects
				( ValidObjects  oGate  oGateDefn  oBlock  oPart  oDesign  oSystem  oPartDefn )
				( NoInherit
					( oGate oPin )
				)
			)
			( Analysis
			)
		)
		( Attribute
			( Name "TOLERANCE" )
			( Description " " )
			( Value
				( DataType ( dString ) )
				( Status  sProperty  sPackage )
			)
			( Objects
				( ValidObjects  oGate  oGateDefn  oBlock  oPart  oDesign  oSystem  oPartDefn )
				( NoInherit
					( oGate oPin )
				)
			)
			( Analysis
			)
		)
		( Attribute
			( Name "WATTAGE" )
			( Description " " )
			( Value
				( DataType ( dString ) )
				( Status  sProperty  sPackage )
			)
			( Objects
				( ValidObjects  oGate  oGateDefn  oBlock  oPart  oDesign  oSystem  oPartDefn )
				( NoInherit
					( oGate oPin )
				)
			)
			( Analysis
			)
		)
		( Attribute
			( Name "CDS_LMAN_SYM_OUTLINE" )
			( Description " " )
			( Value
				( DataType ( dString ) )
				( Status  sProperty  sPackage )
			)
			( Objects
				( ValidObjects  oGate  oGateDefn  oBlock  oPart  oDesign  oSystem  oPartDefn )
				( NoInherit
					( oGate oPin )
				)
			)
			( Analysis
			)
		)
		( Attribute
			( Name "SEC_TYPE" )
			( Description " " )
			( Value
				( DataType ( dString ) )
				( Status  sProperty  sPackage )
			)
			( Objects
				( ValidObjects  oGate  oGateDefn  oBlock  oPart  oDesign  oSystem  oPartDefn )
				( NoInherit
					( oGate oPin )
				)
			)
			( Analysis
			)
		)
		( Attribute
			( Name "$sec" )
			( Description "" )
			( Value
				( DataType ( dString ) )
				( Status  sProperty )
			)
			( Objects
				( ValidObjects  oAll )
			)
			( Analysis
			)
		)
		( Attribute
			( Name "$location" )
			( Description "" )
			( Value
				( DataType ( dString ) )
				( Status  sProperty )
			)
			( Objects
				( ValidObjects  oAll )
			)
			( Analysis
			)
		)
		( Attribute
			( Name "WACKO" )
			( Description " " )
			( Value
				( DataType ( dString ) )
				( Status  sProperty  sPackage )
			)
			( Objects
				( ValidObjects  oGate  oGateDefn  oBlock  oPart  oDesign  oSystem  oPartDefn )
				( NoInherit
					( oGate oPin )
				)
			)
			( Analysis
			)
		)
		( Attribute
			( Name "BODY_TYPE" )
			( Description " " )
			( Value
				( DataType ( dString ) )
				( Status  sProperty  sPackage )
			)
			( Objects
				( ValidObjects  oGate  oBlock  oPart  oDesign  oSystem  oGateDefn  oPartDefn )
			)
			( Analysis
			)
		)
	)
	( designConstraints
		( ruleChanges
			( allRules )
			( design "p3v3"
			)
			( signal "@mstr_symbols.p3v3(sch_1):g"
				( objectFlag fObjectAlias )
				( objectStatus "g" )
			)
			( signal "@mstr_symbols.p3v3(sch_1):page1_g"
				( objectFlag fObjectAlias )
				( objectStatus "page1_g" )
			)
			( signal "@mstr_symbols.p3v3(sch_1):p3v3"
				( alias ( signalRef "@mstr_symbols.p3v3(sch_1):page1_p3v3") )
				( alias ( signalRef "@mstr_symbols.p3v3(sch_1):page1_g") )
				( alias ( signalRef "@mstr_symbols.p3v3(sch_1):g") )
				( objectStatus "p3v3" )
			)
			( signal "@mstr_symbols.p3v3(sch_1):page1_p3v3"
				( objectFlag fObjectAlias )
				( objectStatus "page1_p3v3" )
			)
		)
	)
)
